FILE_TYPE=LIBRARY_PARTS;
primitive 'RS53319LR';
  pin
    'VIN1':
      PIN_NUMBER='(10)';
      PINUSE='POWER';
      NO_LOAD_CHECK='Both';
      NO_IO_CHECK='Both';
      NO_ASSERT_CHECK='TRUE';
      NO_DIR_CHECK='TRUE';
      ALLOW_CONNECT='TRUE';
    'PGOOD':
      PIN_NUMBER='(9)';
      OUTPUT_LOAD='(1.0,-1.0)';
    'PGND':
      PIN_NUMBER='(11_18)';
      PINUSE='POWER';
      NO_LOAD_CHECK='Both';
      NO_IO_CHECK='Both';
      NO_ASSERT_CHECK='TRUE';
      NO_DIR_CHECK='TRUE';
      ALLOW_CONNECT='TRUE';
    'EN':
      PIN_NUMBER='(8)';
      INPUT_LOAD='(-0.01,0.01)';
    'BST':
      PIN_NUMBER='(1)';
      INPUT_LOAD='(-0.01,0.01)';
    'FB':
      PIN_NUMBER='(7)';
      INPUT_LOAD='(-0.01,0.01)';
    'AGND':
      PIN_NUMBER='(2)';
      PINUSE='POWER';
      NO_LOAD_CHECK='Both';
      NO_IO_CHECK='Both';
      NO_ASSERT_CHECK='TRUE';
      NO_DIR_CHECK='TRUE';
      ALLOW_CONNECT='TRUE';
    'VCC':
      PIN_NUMBER='(19)';
      PINUSE='POWER';
      NO_LOAD_CHECK='Both';
      NO_IO_CHECK='Both';
      NO_ASSERT_CHECK='TRUE';
      NO_DIR_CHECK='TRUE';
      ALLOW_CONNECT='TRUE';
    'RTN':
      PIN_NUMBER='(6)';
      PINUSE='POWER';
      NO_LOAD_CHECK='Both';
      NO_IO_CHECK='Both';
      NO_ASSERT_CHECK='TRUE';
      NO_DIR_CHECK='TRUE';
      ALLOW_CONNECT='TRUE';
    'SW':
      PIN_NUMBER='(20)';
      OUTPUT_LOAD='(1.0,-1.0)';
    'REF':
      PIN_NUMBER='(5)';
      INPUT_LOAD='(-0.01,0.01)';
    'MODE':
      PIN_NUMBER='(4)';
      INPUT_LOAD='(-0.01,0.01)';
    'CS':
      PIN_NUMBER='(3)';
      INPUT_LOAD='(-0.01,0.01)';
    'VIN2':
      PIN_NUMBER='(21)';
      PINUSE='POWER';
      NO_LOAD_CHECK='Both';
      NO_IO_CHECK='Both';
      NO_ASSERT_CHECK='TRUE';
      NO_DIR_CHECK='TRUE';
      ALLOW_CONNECT='TRUE';
  end_pin;
  body
    PART_NAME='RS53319LR';
    BODY_NAME='RS53319LR';
    PHYS_DES_PREFIX='U';
    CLASS='IC';
  end_body;
end_primitive;

END.
